# T6G (Grand Teton) — schematic netlist excerpt (pin names and nets, part order shuffled) for the footprints in the layout excerpt that follows; sources: Cadence DE-HDL packaged netlist, KiCad conversion of 04192023_DAF0TMB3IC0_F0TG_MB_C_brd_V02_OCP.brd

R1006  Q_RES  4.7K 5% EMPTY  pkg 0201LF  page 287 : A = MODE_RT_CPU0_P1 ; B = GND
PC81  Q_CAP  22UF 16V 20% X6S  pkg C0805  page 209 : A = SW_P12V_AUX_PVDD18_S5_P0_FLT ; B = GND

J49  SCONN8_G802M0083150RD3HR  IO  pkg HEADER2X4SXN  page 54
  \1\  = CPU1_BP0
  \2\  = GND
  \3\  = CPU1_BP1
  \4\  = GND
  \5\  = CPU1_BP2
  \6\  = GND
  \7\  = CPU1_BP3
  \8\  = GND

(kicad_pcb
	(version 20260206)
	(generator "pcbnew")
	(generator_version "10.0")
	(general
		(thickness 1.6)
		(legacy_teardrops no)
	)
	(paper "A4")
	(title_block
		(title "04192023_DAF0TMB3IC0_F0TG_MB_C_brd_V02_OCP.brd")
		(comment 1 "Grand Teton / footprints 3799-3801 of 8354")
	)
	(layers
		(0 "F.Cu" signal "TOP")
		(4 "In1.Cu" signal "GND")
		(6 "In2.Cu" signal "IN1")
		(8 "In3.Cu" signal "GND1")
		(10 "In4.Cu" signal "IN2")
		(12 "In5.Cu" signal "GND2")
		(14 "In6.Cu" signal "IN3")
		(16 "In7.Cu" signal "GND3")
		(18 "In8.Cu" signal "VCC")
		(20 "In9.Cu" signal "VCC1")
		(22 "In10.Cu" signal "GND4")
		(24 "In11.Cu" signal "IN4")
		(26 "In12.Cu" signal "GND5")
		(28 "In13.Cu" signal "IN5")
		(30 "In14.Cu" signal "GND6")
		(32 "In15.Cu" signal "IN6")
		(34 "In16.Cu" signal "GND7")
		(2 "B.Cu" signal "BOTTOM")
		(9 "F.Adhes" user "F.Adhesive")
		(11 "B.Adhes" user "B.Adhesive")
		(13 "F.Paste" user "Package Geometry/Pastemask Top")
		(15 "B.Paste" user "Package Geometry/Pastemask Bottom")
		(5 "F.SilkS" user "Ref Des/Silkscreen Top")
		(7 "B.SilkS" user "Ref Des/Silkscreen Bottom")
		(1 "F.Mask" user "Board Geometry/Soldermask Top")
		(3 "B.Mask" user "Board Geometry/Soldermask Bottom")
		(17 "Dwgs.User" user "User.Drawings")
		(19 "Cmts.User" user "User.Comments")
		(21 "Eco1.User" user "User.Eco1")
		(23 "Eco2.User" user "User.Eco2")
		(25 "Edge.Cuts" user "Board Geometry/Outline")
		(27 "Margin" user)
		(31 "F.CrtYd" user "Package Geometry/Place Bound Top")
		(29 "B.CrtYd" user "Package Geometry/Place Bound Bottom")
		(35 "F.Fab" user "Ref Des/Assembly Top")
		(33 "B.Fab" user "Ref Des/Assembly Bottom")
	)
	(footprint ""
		(layer "F.Cu")
		(at 28.967684 -52.004214)
		(property "Reference" "J49"
			(at -1.016 -3.495548 0)
			(unlocked yes)
			(layer "F.SilkS")
			(effects
				(font
					(size 0.7874 0.5842)
					(thickness 0.1524)
				)
			)
		)
		(property "Value" ""
			(at 0 0 0)
			(layer "F.Fab")
			(effects
				(font
					(size 1.27 1.27)
				)
			)
		)
		(duplicate_pad_numbers_are_jumpers no)
		(fp_line
			(start -1.700022 -2.739898)
			(end 1.700022 -2.739898)
			(stroke
				(width 0.1524)
				(type default)
			)
			(layer "F.SilkS")
		)
		(fp_line
			(start -1.700022 -2.4257)
			(end -1.700022 -2.739898)
			(stroke
				(width 0.1524)
				(type default)
			)
			(layer "F.SilkS")
		)
		(fp_line
			(start -1.700022 -1.1557)
			(end -1.700022 -1.3843)
			(stroke
				(width 0.1524)
				(type default)
			)
			(layer "F.SilkS")
		)
		(fp_line
			(start -1.700022 0.1143)
			(end -1.700022 -0.1143)
			(stroke
				(width 0.1524)
				(type default)
			)
			(layer "F.SilkS")
		)
		(fp_line
			(start -1.700022 1.3843)
			(end -1.700022 1.1557)
			(stroke
				(width 0.1524)
				(type default)
			)
			(layer "F.SilkS")
		)
		(fp_line
			(start -1.700022 2.739898)
			(end -1.700022 2.4257)
			(stroke
				(width 0.1524)
				(type default)
			)
			(layer "F.SilkS")
		)
		(fp_line
			(start 1.700022 -2.739898)
			(end 1.700022 -2.4257)
			(stroke
				(width 0.1524)
				(type default)
			)
			(layer "F.SilkS")
		)
		(fp_line
			(start 1.700022 -1.3843)
			(end 1.700022 -1.1557)
			(stroke
				(width 0.1524)
				(type default)
			)
			(layer "F.SilkS")
		)
		(fp_line
			(start 1.700022 -0.1143)
			(end 1.700022 0.1143)
			(stroke
				(width 0.1524)
				(type default)
			)
			(layer "F.SilkS")
		)
		(fp_line
			(start 1.700022 1.1557)
			(end 1.700022 1.3843)
			(stroke
				(width 0.1524)
				(type default)
			)
			(layer "F.SilkS")
		)
		(fp_line
			(start 1.700022 2.4257)
			(end 1.700022 2.739898)
			(stroke
				(width 0.1524)
				(type default)
			)
			(layer "F.SilkS")
		)
		(fp_line
			(start 1.700022 2.739898)
			(end -1.700022 2.739898)
			(stroke
				(width 0.1524)
				(type default)
			)
			(layer "F.SilkS")
		)
		(fp_poly
			(pts
				(xy -3.383534 -1.905) (xy -4.399534 -1.397) (xy -4.399534 -2.413)
			)
			(stroke
				(width 0)
				(type default)
			)
			(fill yes)
			(layer "F.SilkS")
		)
		(fp_line
			(start -1.700022 -2.739898)
			(end 1.700022 -2.739898)
			(stroke
				(width 0.1)
				(type default)
			)
			(layer "F.Fab")
		)
		(fp_line
			(start -1.700022 2.739898)
			(end -1.700022 -2.739898)
			(stroke
				(width 0.1)
				(type default)
			)
			(layer "F.Fab")
		)
		(fp_line
			(start 1.700022 -2.739898)
			(end 1.700022 2.739898)
			(stroke
				(width 0.1)
				(type default)
			)
			(layer "F.Fab")
		)
		(fp_line
			(start 1.700022 2.739898)
			(end -1.700022 2.739898)
			(stroke
				(width 0.1)
				(type default)
			)
			(layer "F.Fab")
		)
		(fp_poly
			(pts
				(xy -4.399534 -2.413) (xy -4.399534 -1.397) (xy -3.383534 -1.905)
			)
			(stroke
				(width 0)
				(type default)
			)
			(fill yes)
			(layer "F.Fab")
		)
		(pad "1" smd rect
			(at -2.050034 -1.905 270)
			(size 0.762 2.413)
			(layers "F.Cu" "F.Mask" "F.Paste")
			(net "CPU1_BP0")
		)
		(pad "2" smd rect
			(at 2.050034 -1.905 270)
			(size 0.762 2.413)
			(layers "F.Cu" "F.Mask" "F.Paste")
			(net "GND")
		)
		(pad "3" smd rect
			(at -2.050034 -0.635 270)
			(size 0.762 2.413)
			(layers "F.Cu" "F.Mask" "F.Paste")
			(net "CPU1_BP1")
		)
		(pad "4" smd rect
			(at 2.050034 -0.635 270)
			(size 0.762 2.413)
			(layers "F.Cu" "F.Mask" "F.Paste")
			(net "GND")
		)
		(pad "5" smd rect
			(at -2.050034 0.635 270)
			(size 0.762 2.413)
			(layers "F.Cu" "F.Mask" "F.Paste")
			(net "CPU1_BP2")
		)
		(pad "6" smd rect
			(at 2.050034 0.635 270)
			(size 0.762 2.413)
			(layers "F.Cu" "F.Mask" "F.Paste")
			(net "GND")
		)
		(pad "7" smd rect
			(at -2.050034 1.905 270)
			(size 0.762 2.413)
			(layers "F.Cu" "F.Mask" "F.Paste")
			(net "CPU1_BP3")
		)
		(pad "8" smd rect
			(at 2.050034 1.905 270)
			(size 0.762 2.413)
			(layers "F.Cu" "F.Mask" "F.Paste")
			(net "GND")
		)
	)
	(footprint ""
		(layer "F.Cu")
		(at 334.028288 -402.548852 -90)
		(property "Reference" "R1006"
			(at 0 0 270)
			(layer "F.SilkS")
			(hide yes)
			(effects
				(font
					(size 1.27 1.27)
				)
			)
		)
		(property "Value" ""
			(at 0 0 270)
			(layer "F.Fab")
			(effects
				(font
					(size 1.27 1.27)
				)
			)
		)
		(duplicate_pad_numbers_are_jumpers no)
		(fp_line
			(start -0.32512 0.175006)
			(end -0.32512 -0.175006)
			(stroke
				(width 0.1)
				(type default)
			)
			(layer "F.Fab")
		)
		(fp_line
			(start 0.32512 0.175006)
			(end -0.32512 0.175006)
			(stroke
				(width 0.1)
				(type default)
			)
			(layer "F.Fab")
		)
		(fp_line
			(start -0.32512 -0.175006)
			(end 0.32512 -0.175006)
			(stroke
				(width 0.1)
				(type default)
			)
			(layer "F.Fab")
		)
		(fp_line
			(start 0.32512 -0.175006)
			(end 0.32512 0.175006)
			(stroke
				(width 0.1)
				(type default)
			)
			(layer "F.Fab")
		)
		(pad "1" smd rect
			(at -0.2667 0 270)
			(size 0.3048 0.381)
			(layers "F.Cu" "F.Mask" "F.Paste")
			(net "MODE_RT_CPU0_P1")
		)
		(pad "2" smd rect
			(at 0.2667 0 90)
			(size 0.3048 0.381)
			(layers "F.Cu" "F.Mask" "F.Paste")
			(net "GND")
		)
	)
	(footprint ""
		(layer "F.Cu")
		(at 336.172556 -133.75005)
		(property "Reference" "PC81"
			(at 0 0 0)
			(layer "F.SilkS")
			(hide yes)
			(effects
				(font
					(size 1.27 1.27)
				)
			)
		)
		(property "Value" ""
			(at 0 0 0)
			(layer "F.Fab")
			(effects
				(font
					(size 1.27 1.27)
				)
			)
		)
		(duplicate_pad_numbers_are_jumpers no)
		(fp_line
			(start -1.524 -0.762)
			(end 1.524 -0.762)
			(stroke
				(width 0.1524)
				(type default)
			)
			(layer "F.SilkS")
		)
		(fp_line
			(start -1.524 0.762)
			(end -1.524 -0.762)
			(stroke
				(width 0.1524)
				(type default)
			)
			(layer "F.SilkS")
		)
		(fp_line
			(start 1.524 -0.762)
			(end 1.524 0.762)
			(stroke
				(width 0.1524)
				(type default)
			)
			(layer "F.SilkS")
		)
		(fp_line
			(start 1.524 0.762)
			(end -1.524 0.762)
			(stroke
				(width 0.1524)
				(type default)
			)
			(layer "F.SilkS")
		)
		(fp_line
			(start -1.1049 -0.724916)
			(end -1.1049 0.724916)
			(stroke
				(width 0.1)
				(type default)
			)
			(layer "F.Fab")
		)
		(fp_line
			(start -1.1049 0.724916)
			(end 1.1049 0.724916)
			(stroke
				(width 0.1)
				(type default)
			)
			(layer "F.Fab")
		)
		(fp_line
			(start 1.1049 -0.724916)
			(end -1.1049 -0.724916)
			(stroke
				(width 0.1)
				(type default)
			)
			(layer "F.Fab")
		)
		(fp_line
			(start 1.1049 0.724916)
			(end 1.1049 -0.724916)
			(stroke
				(width 0.1)
				(type default)
			)
			(layer "F.Fab")
		)
		(pad "1" smd rect
			(at -0.889 0 180)
			(size 1.016 1.27)
			(layers "F.Cu" "F.Mask" "F.Paste")
			(net "SW_P12V_AUX_PVDD18_S5_P0_FLT")
		)
		(pad "2" smd rect
			(at 0.889 0 180)
			(size 1.016 1.27)
			(layers "F.Cu" "F.Mask" "F.Paste")
			(net "GND")
		)
	)
)
